# T6G (Grand Teton) — schematic netlist excerpt (pin names and nets, part order shuffled) for the footprints in the layout excerpt that follows; sources: Cadence DE-HDL packaged netlist, KiCad conversion of 04192023_DAF0TMB3IC0_F0TG_MB_C_brd_V02_OCP.brd

C744  Q_CAP_DIFFBUS  DIFF BUS_0.22UF 6.3V 20% X6S  pkg C0201  page 66 : \1\ = P5E_CPU1_P2_TX_C_DN<14> ; \2\ = P5E_CPU1_P2_TX_DN<14>
R1337  Q_RES  0 5% EMPTY  pkg 0402LF  page 159 : A = I3C_SPD_DDRGL_CPU1_BYPASS_SDA ; B = I3C_SPD_DDRGL_CPU1_SDA

DB9  TDR_3P  EMPTY  pkg TH2  page 260
  GND  = T1_GND
  IO1  = TDR_SE_50_OHM_IN2
  IO2  = TDR_SE_50_OHM_IN2

(kicad_pcb
	(version 20260206)
	(generator "pcbnew")
	(generator_version "10.0")
	(general
		(thickness 1.6)
		(legacy_teardrops no)
	)
	(paper "A4")
	(title_block
		(title "04192023_DAF0TMB3IC0_F0TG_MB_C_brd_V02_OCP.brd")
		(comment 1 "Grand Teton / footprints 4325-4327 of 8354")
	)
	(layers
		(0 "F.Cu" signal "TOP")
		(4 "In1.Cu" signal "GND")
		(6 "In2.Cu" signal "IN1")
		(8 "In3.Cu" signal "GND1")
		(10 "In4.Cu" signal "IN2")
		(12 "In5.Cu" signal "GND2")
		(14 "In6.Cu" signal "IN3")
		(16 "In7.Cu" signal "GND3")
		(18 "In8.Cu" signal "VCC")
		(20 "In9.Cu" signal "VCC1")
		(22 "In10.Cu" signal "GND4")
		(24 "In11.Cu" signal "IN4")
		(26 "In12.Cu" signal "GND5")
		(28 "In13.Cu" signal "IN5")
		(30 "In14.Cu" signal "GND6")
		(32 "In15.Cu" signal "IN6")
		(34 "In16.Cu" signal "GND7")
		(2 "B.Cu" signal "BOTTOM")
		(9 "F.Adhes" user "F.Adhesive")
		(11 "B.Adhes" user "B.Adhesive")
		(13 "F.Paste" user "Package Geometry/Pastemask Top")
		(15 "B.Paste" user "Package Geometry/Pastemask Bottom")
		(5 "F.SilkS" user "Ref Des/Silkscreen Top")
		(7 "B.SilkS" user "Ref Des/Silkscreen Bottom")
		(1 "F.Mask" user "Board Geometry/Soldermask Top")
		(3 "B.Mask" user "Board Geometry/Soldermask Bottom")
		(17 "Dwgs.User" user "User.Drawings")
		(19 "Cmts.User" user "User.Comments")
		(21 "Eco1.User" user "User.Eco1")
		(23 "Eco2.User" user "User.Eco2")
		(25 "Edge.Cuts" user "Board Geometry/Outline")
		(27 "Margin" user)
		(31 "F.CrtYd" user "Package Geometry/Place Bound Top")
		(29 "B.CrtYd" user "Package Geometry/Place Bound Bottom")
		(35 "F.Fab" user "Ref Des/Assembly Top")
		(33 "B.Fab" user "Ref Des/Assembly Bottom")
	)
	(footprint ""
		(layer "F.Cu")
		(at 479.262948 -23.903178)
		(property "Reference" "DB9"
			(at 1.276096 2.670556 0)
			(unlocked yes)
			(layer "F.SilkS")
			(effects
				(font
					(size 0.7874 0.5842)
					(thickness 0.1524)
				)
				(justify left)
			)
		)
		(property "Value" ""
			(at 0 0 0)
			(layer "F.Fab")
			(effects
				(font
					(size 1.27 1.27)
				)
			)
		)
		(duplicate_pad_numbers_are_jumpers no)
		(fp_line
			(start -3.330702 -4.771136)
			(end 3.330702 -4.771136)
			(stroke
				(width 0.1524)
				(type default)
			)
			(layer "F.SilkS")
		)
		(fp_line
			(start 0 4.011168)
			(end -3.330702 -4.771136)
			(stroke
				(width 0.1524)
				(type default)
			)
			(layer "F.SilkS")
		)
		(fp_line
			(start 3.330702 -4.771136)
			(end 0 4.011168)
			(stroke
				(width 0.1524)
				(type default)
			)
			(layer "F.SilkS")
		)
		(fp_line
			(start -3.330702 -4.771136)
			(end 3.330702 -4.771136)
			(stroke
				(width 0.1)
				(type default)
			)
			(layer "F.Fab")
		)
		(fp_line
			(start 0 4.011168)
			(end -3.330702 -4.771136)
			(stroke
				(width 0.1)
				(type default)
			)
			(layer "F.Fab")
		)
		(fp_line
			(start 3.330702 -4.771136)
			(end 0 4.011168)
			(stroke
				(width 0.1)
				(type default)
			)
			(layer "F.Fab")
		)
		(pad "1" thru_hole circle
			(at 0 0)
			(size 2.159 2.159)
			(drill 1.7018)
			(layers "*.Cu" "*.Mask")
			(remove_unused_layers no)
			(net "T1_GND")
			(clearance 0.0254)
			(thermal_gap 0.0254)
		)
		(pad "2" thru_hole circle
			(at -1.27 -3.348736)
			(size 2.159 2.159)
			(drill 1.7018)
			(layers "*.Cu" "*.Mask")
			(remove_unused_layers no)
			(net "TDR_SE_50_OHM_IN2")
			(clearance 0.0254)
			(thermal_gap 0.0254)
		)
		(pad "3" thru_hole circle
			(at 1.27 -3.348736)
			(size 2.159 2.159)
			(drill 1.7018)
			(layers "*.Cu" "*.Mask")
			(remove_unused_layers no)
			(net "TDR_SE_50_OHM_IN2")
			(clearance 0.0254)
			(thermal_gap 0.0254)
		)
	)
	(footprint ""
		(layer "F.Cu")
		(at 184.455054 -169.118026 -90)
		(property "Reference" "R1337"
			(at 0 0 270)
			(layer "F.SilkS")
			(hide yes)
			(effects
				(font
					(size 1.27 1.27)
				)
			)
		)
		(property "Value" ""
			(at 0 0 270)
			(layer "F.Fab")
			(effects
				(font
					(size 1.27 1.27)
				)
			)
		)
		(duplicate_pad_numbers_are_jumpers no)
		(fp_line
			(start -0.7874 0.4064)
			(end -0.7874 -0.4064)
			(stroke
				(width 0.1524)
				(type default)
			)
			(layer "F.SilkS")
		)
		(fp_line
			(start 0.7874 0.4064)
			(end -0.7874 0.4064)
			(stroke
				(width 0.1524)
				(type default)
			)
			(layer "F.SilkS")
		)
		(fp_line
			(start -0.7874 -0.4064)
			(end 0.7874 -0.4064)
			(stroke
				(width 0.1524)
				(type default)
			)
			(layer "F.SilkS")
		)
		(fp_line
			(start 0.7874 -0.4064)
			(end 0.7874 0.4064)
			(stroke
				(width 0.1524)
				(type default)
			)
			(layer "F.SilkS")
		)
		(fp_line
			(start -0.67945 0.3048)
			(end -0.67945 -0.305054)
			(stroke
				(width 0.1)
				(type default)
			)
			(layer "F.Fab")
		)
		(fp_line
			(start -0.12065 0.3048)
			(end -0.67945 0.3048)
			(stroke
				(width 0.1)
				(type default)
			)
			(layer "F.Fab")
		)
		(fp_line
			(start 0.120396 0.3048)
			(end 0.120396 0.2794)
			(stroke
				(width 0.1)
				(type default)
			)
			(layer "F.Fab")
		)
		(fp_line
			(start 0.67945 0.3048)
			(end 0.120396 0.3048)
			(stroke
				(width 0.1)
				(type default)
			)
			(layer "F.Fab")
		)
		(fp_line
			(start -0.12065 0.2794)
			(end -0.12065 0.3048)
			(stroke
				(width 0.1)
				(type default)
			)
			(layer "F.Fab")
		)
		(fp_line
			(start 0.120396 0.2794)
			(end -0.12065 0.2794)
			(stroke
				(width 0.1)
				(type default)
			)
			(layer "F.Fab")
		)
		(fp_line
			(start -0.12065 -0.2794)
			(end 0.12065 -0.2794)
			(stroke
				(width 0.1)
				(type default)
			)
			(layer "F.Fab")
		)
		(fp_line
			(start 0.12065 -0.2794)
			(end 0.12065 -0.3048)
			(stroke
				(width 0.1)
				(type default)
			)
			(layer "F.Fab")
		)
		(fp_line
			(start 0.12065 -0.3048)
			(end 0.67945 -0.3048)
			(stroke
				(width 0.1)
				(type default)
			)
			(layer "F.Fab")
		)
		(fp_line
			(start 0.67945 -0.3048)
			(end 0.67945 0.3048)
			(stroke
				(width 0.1)
				(type default)
			)
			(layer "F.Fab")
		)
		(fp_line
			(start -0.67945 -0.305054)
			(end -0.12065 -0.305054)
			(stroke
				(width 0.1)
				(type default)
			)
			(layer "F.Fab")
		)
		(fp_line
			(start -0.12065 -0.305054)
			(end -0.12065 -0.2794)
			(stroke
				(width 0.1)
				(type default)
			)
			(layer "F.Fab")
		)
		(pad "1" smd rect
			(at -0.40005 0 90)
			(size 0.4572 0.508)
			(layers "F.Cu" "F.Mask" "F.Paste")
			(net "I3C_SPD_DDRGL_CPU1_BYPASS_SDA")
		)
		(pad "2" smd rect
			(at 0.40005 0 90)
			(size 0.4572 0.508)
			(layers "F.Cu" "F.Mask" "F.Paste")
			(net "I3C_SPD_DDRGL_CPU1_SDA")
		)
	)
	(footprint ""
		(layer "F.Cu")
		(at 169.368724 -376.982228)
		(property "Reference" "C744"
			(at 0 0 0)
			(layer "F.SilkS")
			(hide yes)
			(effects
				(font
					(size 1.27 1.27)
				)
			)
		)
		(property "Value" ""
			(at 0 0 0)
			(layer "F.Fab")
			(effects
				(font
					(size 1.27 1.27)
				)
			)
		)
		(duplicate_pad_numbers_are_jumpers no)
		(fp_line
			(start -0.299974 -0.150114)
			(end 0.299974 -0.150114)
			(stroke
				(width 0.1)
				(type default)
			)
			(layer "F.Fab")
		)
		(fp_line
			(start -0.299974 0.150114)
			(end -0.299974 -0.150114)
			(stroke
				(width 0.1)
				(type default)
			)
			(layer "F.Fab")
		)
		(fp_line
			(start 0.299974 -0.150114)
			(end 0.299974 0.150114)
			(stroke
				(width 0.1)
				(type default)
			)
			(layer "F.Fab")
		)
		(fp_line
			(start 0.299974 0.150114)
			(end -0.299974 0.150114)
			(stroke
				(width 0.1)
				(type default)
			)
			(layer "F.Fab")
		)
		(pad "1" smd rect
			(at -0.2667 0)
			(size 0.3048 0.381)
			(layers "F.Cu" "F.Mask" "F.Paste")
			(net "P5E_CPU1_P2_TX_C_DN<14>")
		)
		(pad "2" smd rect
			(at 0.2667 0)
			(size 0.3048 0.381)
			(layers "F.Cu" "F.Mask" "F.Paste")
			(net "P5E_CPU1_P2_TX_DN<14>")
		)
	)
)
